(kicad_pcb
	(version 20260206)
	(generator "pcbnew")
	(generator_version "10.0")
	(general
		(thickness 1.6)
		(legacy_teardrops no)
	)
	(paper "A4")
	(title_block
		(title "04192023_DAF0TMB3IC0_F0TG_MB_C_brd_V02_OCP.brd")
		(comment 1 "Grand Teton / footprints 5137-5143 of 8354")
	)
	(layers
		(0 "F.Cu" signal "TOP")
		(4 "In1.Cu" signal "GND")
		(6 "In2.Cu" signal "IN1")
		(8 "In3.Cu" signal "GND1")
		(10 "In4.Cu" signal "IN2")
		(12 "In5.Cu" signal "GND2")
		(14 "In6.Cu" signal "IN3")
		(16 "In7.Cu" signal "GND3")
		(18 "In8.Cu" signal "VCC")
		(20 "In9.Cu" signal "VCC1")
		(22 "In10.Cu" signal "GND4")
		(24 "In11.Cu" signal "IN4")
		(26 "In12.Cu" signal "GND5")
		(28 "In13.Cu" signal "IN5")
		(30 "In14.Cu" signal "GND6")
		(32 "In15.Cu" signal "IN6")
		(34 "In16.Cu" signal "GND7")
		(2 "B.Cu" signal "BOTTOM")
		(9 "F.Adhes" user "F.Adhesive")
		(11 "B.Adhes" user "B.Adhesive")
		(13 "F.Paste" user "Package Geometry/Pastemask Top")
		(15 "B.Paste" user "Package Geometry/Pastemask Bottom")
		(5 "F.SilkS" user "Ref Des/Silkscreen Top")
		(7 "B.SilkS" user "Ref Des/Silkscreen Bottom")
		(1 "F.Mask" user "Board Geometry/Soldermask Top")
		(3 "B.Mask" user "Board Geometry/Soldermask Bottom")
		(17 "Dwgs.User" user "User.Drawings")
		(19 "Cmts.User" user "User.Comments")
		(21 "Eco1.User" user "User.Eco1")
		(23 "Eco2.User" user "User.Eco2")
		(25 "Edge.Cuts" user "Board Geometry/Outline")
		(27 "Margin" user)
		(31 "F.CrtYd" user "Package Geometry/Place Bound Top")
		(29 "B.CrtYd" user "Package Geometry/Place Bound Bottom")
		(35 "F.Fab" user "Ref Des/Assembly Top")
		(33 "B.Fab" user "Ref Des/Assembly Bottom")
	)
	(footprint ""
		(layer "B.Cu")
		(at 134.840218 -41.127426)
		(property "Reference" "C6034"
			(at 0 0 0)
			(layer "B.SilkS")
			(hide yes)
			(effects
				(font
					(size 1.27 1.27)
				)
				(justify mirror)
			)
		)
		(property "Value" ""
			(at 0 0 0)
			(layer "B.Fab")
			(effects
				(font
					(size 1.27 1.27)
				)
				(justify mirror)
			)
		)
		(duplicate_pad_numbers_are_jumpers no)
		(fp_line
			(start -0.7874 -0.4064)
			(end -0.7874 0.4064)
			(stroke
				(width 0.1524)
				(type default)
			)
			(layer "B.SilkS")
		)
		(fp_line
			(start -0.7874 0.4064)
			(end 0.7874 0.4064)
			(stroke
				(width 0.1524)
				(type default)
			)
			(layer "B.SilkS")
		)
		(fp_line
			(start 0.7874 -0.4064)
			(end -0.7874 -0.4064)
			(stroke
				(width 0.1524)
				(type default)
			)
			(layer "B.SilkS")
		)
		(fp_line
			(start 0.7874 0.4064)
			(end 0.7874 -0.4064)
			(stroke
				(width 0.1524)
				(type default)
			)
			(layer "B.SilkS")
		)
		(fp_line
			(start -0.67945 -0.3048)
			(end -0.67945 0.3048)
			(stroke
				(width 0.1)
				(type default)
			)
			(layer "B.Fab")
		)
		(fp_line
			(start -0.67945 0.3048)
			(end -0.120396 0.3048)
			(stroke
				(width 0.1)
				(type default)
			)
			(layer "B.Fab")
		)
		(fp_line
			(start -0.12065 -0.3048)
			(end -0.67945 -0.3048)
			(stroke
				(width 0.1)
				(type default)
			)
			(layer "B.Fab")
		)
		(fp_line
			(start -0.12065 -0.2794)
			(end -0.12065 -0.3048)
			(stroke
				(width 0.1)
				(type default)
			)
			(layer "B.Fab")
		)
		(fp_line
			(start -0.120396 0.2794)
			(end 0.12065 0.2794)
			(stroke
				(width 0.1)
				(type default)
			)
			(layer "B.Fab")
		)
		(fp_line
			(start -0.120396 0.3048)
			(end -0.120396 0.2794)
			(stroke
				(width 0.1)
				(type default)
			)
			(layer "B.Fab")
		)
		(fp_line
			(start 0.12065 -0.305054)
			(end 0.12065 -0.2794)
			(stroke
				(width 0.1)
				(type default)
			)
			(layer "B.Fab")
		)
		(fp_line
			(start 0.12065 -0.2794)
			(end -0.12065 -0.2794)
			(stroke
				(width 0.1)
				(type default)
			)
			(layer "B.Fab")
		)
		(fp_line
			(start 0.12065 0.2794)
			(end 0.12065 0.3048)
			(stroke
				(width 0.1)
				(type default)
			)
			(layer "B.Fab")
		)
		(fp_line
			(start 0.12065 0.3048)
			(end 0.67945 0.3048)
			(stroke
				(width 0.1)
				(type default)
			)
			(layer "B.Fab")
		)
		(fp_line
			(start 0.67945 -0.305054)
			(end 0.12065 -0.305054)
			(stroke
				(width 0.1)
				(type default)
			)
			(layer "B.Fab")
		)
		(fp_line
			(start 0.67945 0.3048)
			(end 0.67945 -0.305054)
			(stroke
				(width 0.1)
				(type default)
			)
			(layer "B.Fab")
		)
		(pad "1" smd circle
			(at 0.40005 0 180)
			(size 0 0)
			(layers "B.Cu" "B.Mask" "B.Paste")
			(net "P1V2_CPU0_USB_DVDD12")
		)
		(pad "2" smd circle
			(at -0.40005 0 180)
			(size 0 0)
			(layers "B.Cu" "B.Mask" "B.Paste")
			(net "GND")
		)
	)
	(footprint ""
		(layer "B.Cu")
		(at 373.369586 -214.523828 90)
		(property "Reference" "R9274"
			(at 0 0 90)
			(layer "B.SilkS")
			(hide yes)
			(effects
				(font
					(size 1.27 1.27)
				)
				(justify mirror)
			)
		)
		(property "Value" ""
			(at 0 0 90)
			(layer "B.Fab")
			(effects
				(font
					(size 1.27 1.27)
				)
				(justify mirror)
			)
		)
		(duplicate_pad_numbers_are_jumpers no)
		(fp_line
			(start 0.7874 -0.4064)
			(end -0.7874 -0.4064)
			(stroke
				(width 0.1524)
				(type default)
			)
			(layer "B.SilkS")
		)
		(fp_line
			(start -0.7874 -0.4064)
			(end -0.7874 -0.065786)
			(stroke
				(width 0.1524)
				(type default)
			)
			(layer "B.SilkS")
		)
		(fp_line
			(start 0.7874 0.010414)
			(end 0.7874 -0.4064)
			(stroke
				(width 0.1524)
				(type default)
			)
			(layer "B.SilkS")
		)
		(fp_line
			(start -0.351028 0.4064)
			(end 0.436372 0.4064)
			(stroke
				(width 0.1524)
				(type default)
			)
			(layer "B.SilkS")
		)
		(fp_line
			(start 0.67945 -0.305054)
			(end 0.12065 -0.305054)
			(stroke
				(width 0.1)
				(type default)
			)
			(layer "B.Fab")
		)
		(fp_line
			(start 0.12065 -0.305054)
			(end 0.12065 -0.2794)
			(stroke
				(width 0.1)
				(type default)
			)
			(layer "B.Fab")
		)
		(fp_line
			(start -0.12065 -0.3048)
			(end -0.67945 -0.3048)
			(stroke
				(width 0.1)
				(type default)
			)
			(layer "B.Fab")
		)
		(fp_line
			(start -0.67945 -0.3048)
			(end -0.67945 0.3048)
			(stroke
				(width 0.1)
				(type default)
			)
			(layer "B.Fab")
		)
		(fp_line
			(start 0.12065 -0.2794)
			(end -0.12065 -0.2794)
			(stroke
				(width 0.1)
				(type default)
			)
			(layer "B.Fab")
		)
		(fp_line
			(start -0.12065 -0.2794)
			(end -0.12065 -0.3048)
			(stroke
				(width 0.1)
				(type default)
			)
			(layer "B.Fab")
		)
		(fp_line
			(start 0.12065 0.2794)
			(end 0.12065 0.3048)
			(stroke
				(width 0.1)
				(type default)
			)
			(layer "B.Fab")
		)
		(fp_line
			(start -0.120396 0.2794)
			(end 0.12065 0.2794)
			(stroke
				(width 0.1)
				(type default)
			)
			(layer "B.Fab")
		)
		(fp_line
			(start 0.67945 0.3048)
			(end 0.67945 -0.305054)
			(stroke
				(width 0.1)
				(type default)
			)
			(layer "B.Fab")
		)
		(fp_line
			(start 0.12065 0.3048)
			(end 0.67945 0.3048)
			(stroke
				(width 0.1)
				(type default)
			)
			(layer "B.Fab")
		)
		(fp_line
			(start -0.120396 0.3048)
			(end -0.120396 0.2794)
			(stroke
				(width 0.1)
				(type default)
			)
			(layer "B.Fab")
		)
		(fp_line
			(start -0.67945 0.3048)
			(end -0.120396 0.3048)
			(stroke
				(width 0.1)
				(type default)
			)
			(layer "B.Fab")
		)
		(pad "1" smd circle
			(at 0.40005 0 270)
			(size 0 0)
			(layers "B.Cu" "B.Mask" "B.Paste")
			(net "CLK_100M_CPU0_CLK04_R_DN")
		)
		(pad "2" smd circle
			(at -0.40005 0 270)
			(size 0 0)
			(layers "B.Cu" "B.Mask" "B.Paste")
			(net "CLK_100M_CPU0_CLK04_DN")
		)
	)
	(footprint ""
		(layer "B.Cu")
		(at 395.881098 -170.458892 180)
		(property "Reference" "PC593_1"
			(at 0 0 0)
			(layer "B.SilkS")
			(hide yes)
			(effects
				(font
					(size 1.27 1.27)
				)
				(justify mirror)
			)
		)
		(property "Value" ""
			(at 0 0 0)
			(layer "B.Fab")
			(effects
				(font
					(size 1.27 1.27)
				)
				(justify mirror)
			)
		)
		(duplicate_pad_numbers_are_jumpers no)
		(fp_line
			(start 1.524 0.762)
			(end 1.524 -0.762)
			(stroke
				(width 0.1524)
				(type default)
			)
			(layer "B.SilkS")
		)
		(fp_line
			(start 1.524 -0.762)
			(end -1.524 -0.762)
			(stroke
				(width 0.1524)
				(type default)
			)
			(layer "B.SilkS")
		)
		(fp_line
			(start -1.524 0.762)
			(end 1.524 0.762)
			(stroke
				(width 0.1524)
				(type default)
			)
			(layer "B.SilkS")
		)
		(fp_line
			(start -1.524 -0.762)
			(end -1.524 0.762)
			(stroke
				(width 0.1524)
				(type default)
			)
			(layer "B.SilkS")
		)
		(fp_line
			(start 1.1049 0.724916)
			(end -1.1049 0.724916)
			(stroke
				(width 0.1)
				(type default)
			)
			(layer "B.Fab")
		)
		(fp_line
			(start 1.1049 -0.724916)
			(end 1.1049 0.724916)
			(stroke
				(width 0.1)
				(type default)
			)
			(layer "B.Fab")
		)
		(fp_line
			(start -1.1049 0.724916)
			(end -1.1049 -0.724916)
			(stroke
				(width 0.1)
				(type default)
			)
			(layer "B.Fab")
		)
		(fp_line
			(start -1.1049 -0.724916)
			(end 1.1049 -0.724916)
			(stroke
				(width 0.1)
				(type default)
			)
			(layer "B.Fab")
		)
		(pad "1" smd rect
			(at 0.889 0 180)
			(size 1.016 1.27)
			(layers "B.Cu" "B.Mask" "B.Paste")
			(net "SW_P12V_AUX_PVDDCR_SOC_P0_FLT")
		)
		(pad "2" smd rect
			(at -0.889 0 180)
			(size 1.016 1.27)
			(layers "B.Cu" "B.Mask" "B.Paste")
			(net "GND")
		)
	)
	(footprint ""
		(layer "B.Cu")
		(at 395.252194 -203.882498 -90)
		(property "Reference" "R6132"
			(at 0 0 90)
			(layer "B.SilkS")
			(hide yes)
			(effects
				(font
					(size 1.27 1.27)
				)
				(justify mirror)
			)
		)
		(property "Value" ""
			(at 0 0 90)
			(layer "B.Fab")
			(effects
				(font
					(size 1.27 1.27)
				)
				(justify mirror)
			)
		)
		(duplicate_pad_numbers_are_jumpers no)
		(fp_line
			(start -0.7874 0.4064)
			(end 0.7874 0.4064)
			(stroke
				(width 0.1524)
				(type default)
			)
			(layer "B.SilkS")
		)
		(fp_line
			(start 0.7874 0.4064)
			(end 0.7874 -0.4064)
			(stroke
				(width 0.1524)
				(type default)
			)
			(layer "B.SilkS")
		)
		(fp_line
			(start -0.7874 -0.4064)
			(end -0.7874 0.4064)
			(stroke
				(width 0.1524)
				(type default)
			)
			(layer "B.SilkS")
		)
		(fp_line
			(start 0.7874 -0.4064)
			(end -0.7874 -0.4064)
			(stroke
				(width 0.1524)
				(type default)
			)
			(layer "B.SilkS")
		)
		(fp_line
			(start -0.67945 0.3048)
			(end -0.120396 0.3048)
			(stroke
				(width 0.1)
				(type default)
			)
			(layer "B.Fab")
		)
		(fp_line
			(start -0.120396 0.3048)
			(end -0.120396 0.2794)
			(stroke
				(width 0.1)
				(type default)
			)
			(layer "B.Fab")
		)
		(fp_line
			(start 0.12065 0.3048)
			(end 0.67945 0.3048)
			(stroke
				(width 0.1)
				(type default)
			)
			(layer "B.Fab")
		)
		(fp_line
			(start 0.67945 0.3048)
			(end 0.67945 -0.305054)
			(stroke
				(width 0.1)
				(type default)
			)
			(layer "B.Fab")
		)
		(fp_line
			(start -0.120396 0.2794)
			(end 0.12065 0.2794)
			(stroke
				(width 0.1)
				(type default)
			)
			(layer "B.Fab")
		)
		(fp_line
			(start 0.12065 0.2794)
			(end 0.12065 0.3048)
			(stroke
				(width 0.1)
				(type default)
			)
			(layer "B.Fab")
		)
		(fp_line
			(start -0.12065 -0.2794)
			(end -0.12065 -0.3048)
			(stroke
				(width 0.1)
				(type default)
			)
			(layer "B.Fab")
		)
		(fp_line
			(start 0.12065 -0.2794)
			(end -0.12065 -0.2794)
			(stroke
				(width 0.1)
				(type default)
			)
			(layer "B.Fab")
		)
		(fp_line
			(start -0.67945 -0.3048)
			(end -0.67945 0.3048)
			(stroke
				(width 0.1)
				(type default)
			)
			(layer "B.Fab")
		)
		(fp_line
			(start -0.12065 -0.3048)
			(end -0.67945 -0.3048)
			(stroke
				(width 0.1)
				(type default)
			)
			(layer "B.Fab")
		)
		(fp_line
			(start 0.12065 -0.305054)
			(end 0.12065 -0.2794)
			(stroke
				(width 0.1)
				(type default)
			)
			(layer "B.Fab")
		)
		(fp_line
			(start 0.67945 -0.305054)
			(end 0.12065 -0.305054)
			(stroke
				(width 0.1)
				(type default)
			)
			(layer "B.Fab")
		)
		(pad "1" smd circle
			(at 0.40005 0 90)
			(size 0 0)
			(layers "B.Cu" "B.Mask" "B.Paste")
			(net "PVDD18_S5_P0")
		)
		(pad "2" smd circle
			(at -0.40005 0 90)
			(size 0 0)
			(layers "B.Cu" "B.Mask" "B.Paste")
			(net "FAB_REV_ID0")
		)
	)
	(footprint ""
		(layer "B.Cu")
		(at 392.016234 -395.466062 -90)
		(property "Reference" "C991"
			(at 0 0 90)
			(layer "B.SilkS")
			(hide yes)
			(effects
				(font
					(size 1.27 1.27)
				)
				(justify mirror)
			)
		)
		(property "Value" ""
			(at 0 0 90)
			(layer "B.Fab")
			(effects
				(font
					(size 1.27 1.27)
				)
				(justify mirror)
			)
		)
		(duplicate_pad_numbers_are_jumpers no)
		(fp_line
			(start -1.524 0.762)
			(end 1.524 0.762)
			(stroke
				(width 0.1524)
				(type default)
			)
			(layer "B.SilkS")
		)
		(fp_line
			(start 1.524 0.762)
			(end 1.524 -0.762)
			(stroke
				(width 0.1524)
				(type default)
			)
			(layer "B.SilkS")
		)
		(fp_line
			(start -1.524 -0.762)
			(end -1.524 0.762)
			(stroke
				(width 0.1524)
				(type default)
			)
			(layer "B.SilkS")
		)
		(fp_line
			(start 1.524 -0.762)
			(end -1.524 -0.762)
			(stroke
				(width 0.1524)
				(type default)
			)
			(layer "B.SilkS")
		)
		(fp_line
			(start -1.1049 0.724916)
			(end -1.1049 -0.724916)
			(stroke
				(width 0.1)
				(type default)
			)
			(layer "B.Fab")
		)
		(fp_line
			(start 1.1049 0.724916)
			(end -1.1049 0.724916)
			(stroke
				(width 0.1)
				(type default)
			)
			(layer "B.Fab")
		)
		(fp_line
			(start -1.1049 -0.724916)
			(end 1.1049 -0.724916)
			(stroke
				(width 0.1)
				(type default)
			)
			(layer "B.Fab")
		)
		(fp_line
			(start 1.1049 -0.724916)
			(end 1.1049 0.724916)
			(stroke
				(width 0.1)
				(type default)
			)
			(layer "B.Fab")
		)
		(pad "1" smd rect
			(at 0.889 0 270)
			(size 1.016 1.27)
			(layers "B.Cu" "B.Mask" "B.Paste")
			(net "P1V8_CPU0_RT3_1A")
		)
		(pad "2" smd rect
			(at -0.889 0 270)
			(size 1.016 1.27)
			(layers "B.Cu" "B.Mask" "B.Paste")
			(net "GND")
		)
	)
	(footprint ""
		(layer "B.Cu")
		(at 56.073802 -193.996564)
		(property "Reference" "R103"
			(at 0 0 0)
			(layer "B.SilkS")
			(hide yes)
			(effects
				(font
					(size 1.27 1.27)
				)
				(justify mirror)
			)
		)
		(property "Value" ""
			(at 0 0 0)
			(layer "B.Fab")
			(effects
				(font
					(size 1.27 1.27)
				)
				(justify mirror)
			)
		)
		(duplicate_pad_numbers_are_jumpers no)
		(fp_line
			(start -0.7874 -0.4064)
			(end -0.7874 0.4064)
			(stroke
				(width 0.1524)
				(type default)
			)
			(layer "B.SilkS")
		)
		(fp_line
			(start -0.7874 0.4064)
			(end 0.7874 0.4064)
			(stroke
				(width 0.1524)
				(type default)
			)
			(layer "B.SilkS")
		)
		(fp_line
			(start 0.7874 -0.4064)
			(end -0.7874 -0.4064)
			(stroke
				(width 0.1524)
				(type default)
			)
			(layer "B.SilkS")
		)
		(fp_line
			(start 0.7874 0.4064)
			(end 0.7874 -0.4064)
			(stroke
				(width 0.1524)
				(type default)
			)
			(layer "B.SilkS")
		)
		(fp_line
			(start -0.67945 -0.3048)
			(end -0.67945 0.3048)
			(stroke
				(width 0.1)
				(type default)
			)
			(layer "B.Fab")
		)
		(fp_line
			(start -0.67945 0.3048)
			(end -0.120396 0.3048)
			(stroke
				(width 0.1)
				(type default)
			)
			(layer "B.Fab")
		)
		(fp_line
			(start -0.12065 -0.3048)
			(end -0.67945 -0.3048)
			(stroke
				(width 0.1)
				(type default)
			)
			(layer "B.Fab")
		)
		(fp_line
			(start -0.12065 -0.2794)
			(end -0.12065 -0.3048)
			(stroke
				(width 0.1)
				(type default)
			)
			(layer "B.Fab")
		)
		(fp_line
			(start -0.120396 0.2794)
			(end 0.12065 0.2794)
			(stroke
				(width 0.1)
				(type default)
			)
			(layer "B.Fab")
		)
		(fp_line
			(start -0.120396 0.3048)
			(end -0.120396 0.2794)
			(stroke
				(width 0.1)
				(type default)
			)
			(layer "B.Fab")
		)
		(fp_line
			(start 0.12065 -0.305054)
			(end 0.12065 -0.2794)
			(stroke
				(width 0.1)
				(type default)
			)
			(layer "B.Fab")
		)
		(fp_line
			(start 0.12065 -0.2794)
			(end -0.12065 -0.2794)
			(stroke
				(width 0.1)
				(type default)
			)
			(layer "B.Fab")
		)
		(fp_line
			(start 0.12065 0.2794)
			(end 0.12065 0.3048)
			(stroke
				(width 0.1)
				(type default)
			)
			(layer "B.Fab")
		)
		(fp_line
			(start 0.12065 0.3048)
			(end 0.67945 0.3048)
			(stroke
				(width 0.1)
				(type default)
			)
			(layer "B.Fab")
		)
		(fp_line
			(start 0.67945 -0.305054)
			(end 0.12065 -0.305054)
			(stroke
				(width 0.1)
				(type default)
			)
			(layer "B.Fab")
		)
		(fp_line
			(start 0.67945 0.3048)
			(end 0.67945 -0.305054)
			(stroke
				(width 0.1)
				(type default)
			)
			(layer "B.Fab")
		)
		(pad "1" smd circle
			(at 0.40005 0 180)
			(size 0 0)
			(layers "B.Cu" "B.Mask" "B.Paste")
			(net "P3V3")
		)
		(pad "2" smd circle
			(at -0.40005 0 180)
			(size 0 0)
			(layers "B.Cu" "B.Mask" "B.Paste")
			(net "PWRGD_CHA_CPU1_DIMM0")
		)
	)
	(footprint ""
		(layer "B.Cu")
		(at 369.900454 -268.41831)
		(property "Reference" "C2214"
			(at 0 0 0)
			(layer "B.SilkS")
			(hide yes)
			(effects
				(font
					(size 1.27 1.27)
				)
				(justify mirror)
			)
		)
		(property "Value" ""
			(at 0 0 0)
			(layer "B.Fab")
			(effects
				(font
					(size 1.27 1.27)
				)
				(justify mirror)
			)
		)
		(duplicate_pad_numbers_are_jumpers no)
		(fp_line
			(start -0.7874 -0.4064)
			(end -0.7874 0.4064)
			(stroke
				(width 0.1524)
				(type default)
			)
			(layer "B.SilkS")
		)
		(fp_line
			(start -0.7874 0.4064)
			(end 0.7874 0.4064)
			(stroke
				(width 0.1524)
				(type default)
			)
			(layer "B.SilkS")
		)
		(fp_line
			(start 0.7874 -0.4064)
			(end -0.7874 -0.4064)
			(stroke
				(width 0.1524)
				(type default)
			)
			(layer "B.SilkS")
		)
		(fp_line
			(start 0.7874 0.4064)
			(end 0.7874 -0.4064)
			(stroke
				(width 0.1524)
				(type default)
			)
			(layer "B.SilkS")
		)
		(fp_line
			(start -0.67945 -0.3048)
			(end -0.67945 0.3048)
			(stroke
				(width 0.1)
				(type default)
			)
			(layer "B.Fab")
		)
		(fp_line
			(start -0.67945 0.3048)
			(end -0.120396 0.3048)
			(stroke
				(width 0.1)
				(type default)
			)
			(layer "B.Fab")
		)
		(fp_line
			(start -0.12065 -0.3048)
			(end -0.67945 -0.3048)
			(stroke
				(width 0.1)
				(type default)
			)
			(layer "B.Fab")
		)
		(fp_line
			(start -0.12065 -0.2794)
			(end -0.12065 -0.3048)
			(stroke
				(width 0.1)
				(type default)
			)
			(layer "B.Fab")
		)
		(fp_line
			(start -0.120396 0.2794)
			(end 0.12065 0.2794)
			(stroke
				(width 0.1)
				(type default)
			)
			(layer "B.Fab")
		)
		(fp_line
			(start -0.120396 0.3048)
			(end -0.120396 0.2794)
			(stroke
				(width 0.1)
				(type default)
			)
			(layer "B.Fab")
		)
		(fp_line
			(start 0.12065 -0.305054)
			(end 0.12065 -0.2794)
			(stroke
				(width 0.1)
				(type default)
			)
			(layer "B.Fab")
		)
		(fp_line
			(start 0.12065 -0.2794)
			(end -0.12065 -0.2794)
			(stroke
				(width 0.1)
				(type default)
			)
			(layer "B.Fab")
		)
		(fp_line
			(start 0.12065 0.2794)
			(end 0.12065 0.3048)
			(stroke
				(width 0.1)
				(type default)
			)
			(layer "B.Fab")
		)
		(fp_line
			(start 0.12065 0.3048)
			(end 0.67945 0.3048)
			(stroke
				(width 0.1)
				(type default)
			)
			(layer "B.Fab")
		)
		(fp_line
			(start 0.67945 -0.305054)
			(end 0.12065 -0.305054)
			(stroke
				(width 0.1)
				(type default)
			)
			(layer "B.Fab")
		)
		(fp_line
			(start 0.67945 0.3048)
			(end 0.67945 -0.305054)
			(stroke
				(width 0.1)
				(type default)
			)
			(layer "B.Fab")
		)
		(pad "1" smd circle
			(at 0.40005 0 180)
			(size 0 0)
			(layers "B.Cu" "B.Mask" "B.Paste")
			(net "PVDDCR_CPU1_P0")
		)
		(pad "2" smd circle
			(at -0.40005 0 180)
			(size 0 0)
			(layers "B.Cu" "B.Mask" "B.Paste")
			(net "GND")
		)
	)
)
